# T6G (Grand Teton) — schematic netlist excerpt (pin names and nets, part order shuffled) for the footprints in the layout excerpt that follows; sources: Cadence DE-HDL packaged netlist, KiCad conversion of 04192023_DAF0TMB3IC0_F0TG_MB_C_brd_V02_OCP.brd

R278  Q_RES  0 5% CHIP  pkg 0402LF  page 82 : A = FM_PVDD11_S3_P1_OCP_N ; B = PVDD11_S3_P1_OCP_N
R6813  Q_RES  0 5% CHIP  pkg 0201LF  page 320 : A = SMB_RT_CPU1_P0_R_SDA ; B = SMB_RT_CPU1_P0_R2_SDA
R453  Q_RES  10K 5% CHIP  pkg 0402LF  page 192 : A = PVDD_33_S5_VCC ; B = PWRGD_PVDD33_S5

(kicad_pcb
	(version 20260206)
	(generator "pcbnew")
	(generator_version "10.0")
	(general
		(thickness 1.6)
		(legacy_teardrops no)
	)
	(paper "A4")
	(title_block
		(title "04192023_DAF0TMB3IC0_F0TG_MB_C_brd_V02_OCP.brd")
		(comment 1 "Grand Teton / footprints 6874-6876 of 8354")
	)
	(layers
		(0 "F.Cu" signal "TOP")
		(4 "In1.Cu" signal "GND")
		(6 "In2.Cu" signal "IN1")
		(8 "In3.Cu" signal "GND1")
		(10 "In4.Cu" signal "IN2")
		(12 "In5.Cu" signal "GND2")
		(14 "In6.Cu" signal "IN3")
		(16 "In7.Cu" signal "GND3")
		(18 "In8.Cu" signal "VCC")
		(20 "In9.Cu" signal "VCC1")
		(22 "In10.Cu" signal "GND4")
		(24 "In11.Cu" signal "IN4")
		(26 "In12.Cu" signal "GND5")
		(28 "In13.Cu" signal "IN5")
		(30 "In14.Cu" signal "GND6")
		(32 "In15.Cu" signal "IN6")
		(34 "In16.Cu" signal "GND7")
		(2 "B.Cu" signal "BOTTOM")
		(9 "F.Adhes" user "F.Adhesive")
		(11 "B.Adhes" user "B.Adhesive")
		(13 "F.Paste" user "Package Geometry/Pastemask Top")
		(15 "B.Paste" user "Package Geometry/Pastemask Bottom")
		(5 "F.SilkS" user "Ref Des/Silkscreen Top")
		(7 "B.SilkS" user "Ref Des/Silkscreen Bottom")
		(1 "F.Mask" user "Board Geometry/Soldermask Top")
		(3 "B.Mask" user "Board Geometry/Soldermask Bottom")
		(17 "Dwgs.User" user "User.Drawings")
		(19 "Cmts.User" user "User.Comments")
		(21 "Eco1.User" user "User.Eco1")
		(23 "Eco2.User" user "User.Eco2")
		(25 "Edge.Cuts" user "Board Geometry/Outline")
		(27 "Margin" user)
		(31 "F.CrtYd" user "Package Geometry/Place Bound Top")
		(29 "B.CrtYd" user "Package Geometry/Place Bound Bottom")
		(35 "F.Fab" user "Ref Des/Assembly Top")
		(33 "B.Fab" user "Ref Des/Assembly Bottom")
	)
	(footprint ""
		(layer "B.Cu")
		(at 214.122 -334.01)
		(property "Reference" "R6813"
			(at 0 0 0)
			(layer "B.SilkS")
			(hide yes)
			(effects
				(font
					(size 1.27 1.27)
				)
				(justify mirror)
			)
		)
		(property "Value" ""
			(at 0 0 0)
			(layer "B.Fab")
			(effects
				(font
					(size 1.27 1.27)
				)
				(justify mirror)
			)
		)
		(duplicate_pad_numbers_are_jumpers no)
		(fp_line
			(start -0.32512 -0.175006)
			(end -0.32512 0.175006)
			(stroke
				(width 0.1)
				(type default)
			)
			(layer "B.Fab")
		)
		(fp_line
			(start -0.32512 0.175006)
			(end 0.32512 0.175006)
			(stroke
				(width 0.1)
				(type default)
			)
			(layer "B.Fab")
		)
		(fp_line
			(start 0.32512 -0.175006)
			(end -0.32512 -0.175006)
			(stroke
				(width 0.1)
				(type default)
			)
			(layer "B.Fab")
		)
		(fp_line
			(start 0.32512 0.175006)
			(end 0.32512 -0.175006)
			(stroke
				(width 0.1)
				(type default)
			)
			(layer "B.Fab")
		)
		(pad "1" smd rect
			(at 0.2667 0 180)
			(size 0.3048 0.381)
			(layers "B.Cu" "B.Mask" "B.Paste")
			(net "SMB_RT_CPU1_P0_R_SDA")
		)
		(pad "2" smd rect
			(at -0.2667 0)
			(size 0.3048 0.381)
			(layers "B.Cu" "B.Mask" "B.Paste")
			(net "SMB_RT_CPU1_P0_R2_SDA")
		)
	)
	(footprint ""
		(layer "B.Cu")
		(at 180.721 -100.294948 90)
		(property "Reference" "R278"
			(at 0 0 90)
			(layer "B.SilkS")
			(hide yes)
			(effects
				(font
					(size 1.27 1.27)
				)
				(justify mirror)
			)
		)
		(property "Value" ""
			(at 0 0 90)
			(layer "B.Fab")
			(effects
				(font
					(size 1.27 1.27)
				)
				(justify mirror)
			)
		)
		(duplicate_pad_numbers_are_jumpers no)
		(fp_line
			(start 0.7874 -0.4064)
			(end -0.7874 -0.4064)
			(stroke
				(width 0.1524)
				(type default)
			)
			(layer "B.SilkS")
		)
		(fp_line
			(start -0.7874 -0.4064)
			(end -0.7874 0.4064)
			(stroke
				(width 0.1524)
				(type default)
			)
			(layer "B.SilkS")
		)
		(fp_line
			(start 0.7874 0.4064)
			(end 0.7874 -0.4064)
			(stroke
				(width 0.1524)
				(type default)
			)
			(layer "B.SilkS")
		)
		(fp_line
			(start -0.7874 0.4064)
			(end 0.7874 0.4064)
			(stroke
				(width 0.1524)
				(type default)
			)
			(layer "B.SilkS")
		)
		(fp_line
			(start 0.67945 -0.305054)
			(end 0.12065 -0.305054)
			(stroke
				(width 0.1)
				(type default)
			)
			(layer "B.Fab")
		)
		(fp_line
			(start 0.12065 -0.305054)
			(end 0.12065 -0.2794)
			(stroke
				(width 0.1)
				(type default)
			)
			(layer "B.Fab")
		)
		(fp_line
			(start -0.12065 -0.3048)
			(end -0.67945 -0.3048)
			(stroke
				(width 0.1)
				(type default)
			)
			(layer "B.Fab")
		)
		(fp_line
			(start -0.67945 -0.3048)
			(end -0.67945 0.3048)
			(stroke
				(width 0.1)
				(type default)
			)
			(layer "B.Fab")
		)
		(fp_line
			(start 0.12065 -0.2794)
			(end -0.12065 -0.2794)
			(stroke
				(width 0.1)
				(type default)
			)
			(layer "B.Fab")
		)
		(fp_line
			(start -0.12065 -0.2794)
			(end -0.12065 -0.3048)
			(stroke
				(width 0.1)
				(type default)
			)
			(layer "B.Fab")
		)
		(fp_line
			(start 0.12065 0.2794)
			(end 0.12065 0.3048)
			(stroke
				(width 0.1)
				(type default)
			)
			(layer "B.Fab")
		)
		(fp_line
			(start -0.120396 0.2794)
			(end 0.12065 0.2794)
			(stroke
				(width 0.1)
				(type default)
			)
			(layer "B.Fab")
		)
		(fp_line
			(start 0.67945 0.3048)
			(end 0.67945 -0.305054)
			(stroke
				(width 0.1)
				(type default)
			)
			(layer "B.Fab")
		)
		(fp_line
			(start 0.12065 0.3048)
			(end 0.67945 0.3048)
			(stroke
				(width 0.1)
				(type default)
			)
			(layer "B.Fab")
		)
		(fp_line
			(start -0.120396 0.3048)
			(end -0.120396 0.2794)
			(stroke
				(width 0.1)
				(type default)
			)
			(layer "B.Fab")
		)
		(fp_line
			(start -0.67945 0.3048)
			(end -0.120396 0.3048)
			(stroke
				(width 0.1)
				(type default)
			)
			(layer "B.Fab")
		)
		(pad "1" smd circle
			(at 0.40005 0 270)
			(size 0 0)
			(layers "B.Cu" "B.Mask" "B.Paste")
			(net "FM_PVDD11_S3_P1_OCP_N")
		)
		(pad "2" smd circle
			(at -0.40005 0 270)
			(size 0 0)
			(layers "B.Cu" "B.Mask" "B.Paste")
			(net "PVDD11_S3_P1_OCP_N")
		)
	)
	(footprint ""
		(layer "B.Cu")
		(at 202.15225 -341.864442 180)
		(property "Reference" "R453"
			(at 0 0 0)
			(layer "B.SilkS")
			(hide yes)
			(effects
				(font
					(size 1.27 1.27)
				)
				(justify mirror)
			)
		)
		(property "Value" ""
			(at 0 0 0)
			(layer "B.Fab")
			(effects
				(font
					(size 1.27 1.27)
				)
				(justify mirror)
			)
		)
		(duplicate_pad_numbers_are_jumpers no)
		(fp_line
			(start 0.7874 0.4064)
			(end 0.7874 -0.4064)
			(stroke
				(width 0.1524)
				(type default)
			)
			(layer "B.SilkS")
		)
		(fp_line
			(start 0.7874 -0.4064)
			(end -0.7874 -0.4064)
			(stroke
				(width 0.1524)
				(type default)
			)
			(layer "B.SilkS")
		)
		(fp_line
			(start -0.7874 0.4064)
			(end 0.7874 0.4064)
			(stroke
				(width 0.1524)
				(type default)
			)
			(layer "B.SilkS")
		)
		(fp_line
			(start -0.7874 -0.4064)
			(end -0.7874 0.4064)
			(stroke
				(width 0.1524)
				(type default)
			)
			(layer "B.SilkS")
		)
		(fp_line
			(start 0.67945 0.3048)
			(end 0.67945 -0.305054)
			(stroke
				(width 0.1)
				(type default)
			)
			(layer "B.Fab")
		)
		(fp_line
			(start 0.67945 -0.305054)
			(end 0.12065 -0.305054)
			(stroke
				(width 0.1)
				(type default)
			)
			(layer "B.Fab")
		)
		(fp_line
			(start 0.12065 0.3048)
			(end 0.67945 0.3048)
			(stroke
				(width 0.1)
				(type default)
			)
			(layer "B.Fab")
		)
		(fp_line
			(start 0.12065 0.2794)
			(end 0.12065 0.3048)
			(stroke
				(width 0.1)
				(type default)
			)
			(layer "B.Fab")
		)
		(fp_line
			(start 0.12065 -0.2794)
			(end -0.12065 -0.2794)
			(stroke
				(width 0.1)
				(type default)
			)
			(layer "B.Fab")
		)
		(fp_line
			(start 0.12065 -0.305054)
			(end 0.12065 -0.2794)
			(stroke
				(width 0.1)
				(type default)
			)
			(layer "B.Fab")
		)
		(fp_line
			(start -0.120396 0.3048)
			(end -0.120396 0.2794)
			(stroke
				(width 0.1)
				(type default)
			)
			(layer "B.Fab")
		)
		(fp_line
			(start -0.120396 0.2794)
			(end 0.12065 0.2794)
			(stroke
				(width 0.1)
				(type default)
			)
			(layer "B.Fab")
		)
		(fp_line
			(start -0.12065 -0.2794)
			(end -0.12065 -0.3048)
			(stroke
				(width 0.1)
				(type default)
			)
			(layer "B.Fab")
		)
		(fp_line
			(start -0.12065 -0.3048)
			(end -0.67945 -0.3048)
			(stroke
				(width 0.1)
				(type default)
			)
			(layer "B.Fab")
		)
		(fp_line
			(start -0.67945 0.3048)
			(end -0.120396 0.3048)
			(stroke
				(width 0.1)
				(type default)
			)
			(layer "B.Fab")
		)
		(fp_line
			(start -0.67945 -0.3048)
			(end -0.67945 0.3048)
			(stroke
				(width 0.1)
				(type default)
			)
			(layer "B.Fab")
		)
		(pad "1" smd circle
			(at 0.40005 0)
			(size 0 0)
			(layers "B.Cu" "B.Mask" "B.Paste")
			(net "PVDD_33_S5_VCC")
		)
		(pad "2" smd circle
			(at -0.40005 0)
			(size 0 0)
			(layers "B.Cu" "B.Mask" "B.Paste")
			(net "PWRGD_PVDD33_S5")
		)
	)
)
